# BASEBOARD_FAB2 (Tioga Pass) — schematic netlist excerpt (pin names and nets, part order shuffled) for the footprints in the layout excerpt that follows; sources: Cadence DE-HDL packaged netlist, KiCad conversion of Wiwynn_Tioga_Pass_MB.brd

C25W43  CAP  1.0UF 16V 10% X6S  pkg 0402  page 149 : A = VCC_D_3V3 ; B = GND

(kicad_pcb
	(version 20260206)
	(generator "pcbnew")
	(generator_version "10.0")
	(general
		(thickness 1.6)
		(legacy_teardrops no)
	)
	(paper "A4")
	(title_block
		(title "Wiwynn_Tioga_Pass_MB.brd")
		(comment 1 "Tioga Pass / footprints 4128-4128 of 4770")
	)
	(layers
		(0 "F.Cu" signal "TOP")
		(4 "In1.Cu" signal "L2GND")
		(6 "In2.Cu" signal "L3")
		(8 "In3.Cu" signal "L4GND")
		(10 "In4.Cu" signal "L5")
		(12 "In5.Cu" signal "L6GND")
		(14 "In6.Cu" signal "L7VCC")
		(16 "In7.Cu" signal "L8VCC")
		(18 "In8.Cu" signal "L9GND")
		(20 "In9.Cu" signal "L10")
		(22 "In10.Cu" signal "L11GND")
		(24 "In11.Cu" signal "L12")
		(26 "In12.Cu" signal "L13GND")
		(2 "B.Cu" signal "BOTTOM")
		(9 "F.Adhes" user "F.Adhesive")
		(11 "B.Adhes" user "B.Adhesive")
		(13 "F.Paste" user "Package Geometry/Pastemask Top")
		(15 "B.Paste" user "Package Geometry/Pastemask Bottom")
		(5 "F.SilkS" user "Ref Des/Silkscreen Top")
		(7 "B.SilkS" user "Ref Des/Silkscreen Bottom")
		(1 "F.Mask" user "Board Geometry/Soldermask Top")
		(3 "B.Mask" user "Board Geometry/Soldermask Bottom")
		(17 "Dwgs.User" user "User.Drawings")
		(19 "Cmts.User" user "User.Comments")
		(21 "Eco1.User" user "User.Eco1")
		(23 "Eco2.User" user "User.Eco2")
		(25 "Edge.Cuts" user "Board Geometry/Outline")
		(27 "Margin" user)
		(31 "F.CrtYd" user "Package Geometry/Place Bound Top")
		(29 "B.CrtYd" user "Package Geometry/Place Bound Bottom")
		(35 "F.Fab" user "Ref Des/Assembly Top")
		(33 "B.Fab" user "Ref Des/Assembly Bottom")
	)
	(footprint ""
		(layer "B.Cu")
		(at 418.61486 -30.13456 90)
		(property "Reference" "C25W43"
			(at 0.8382 -0.67818 90)
			(unlocked yes)
			(layer "B.SilkS")
			(effects
				(font
					(size 0.4064 0.254)
					(thickness 0.1524)
				)
				(justify left mirror)
			)
		)
		(property "Value" ""
			(at 0 0 90)
			(layer "B.Fab")
			(effects
				(font
					(size 1.27 1.27)
				)
				(justify mirror)
			)
		)
		(duplicate_pad_numbers_are_jumpers no)
		(fp_poly
			(pts
				(xy -0.3048 -0.1016) (xy -0.3048 0.9906) (xy 0.3048 0.9906) (xy 0.3048 -0.1016)
			)
			(stroke
				(width 0)
				(type default)
			)
			(fill no)
			(layer "B.CrtYd")
		)
		(fp_line
			(start 0.3048 -0.1016)
			(end 0.3048 0.9906)
			(stroke
				(width 0.1)
				(type default)
			)
			(layer "B.Fab")
		)
		(fp_line
			(start -0.3048 -0.1016)
			(end 0.3048 -0.1016)
			(stroke
				(width 0.1)
				(type default)
			)
			(layer "B.Fab")
		)
		(fp_line
			(start 0.3048 0.9906)
			(end -0.3048 0.9906)
			(stroke
				(width 0.1)
				(type default)
			)
			(layer "B.Fab")
		)
		(fp_line
			(start -0.3048 0.9906)
			(end -0.3048 -0.1016)
			(stroke
				(width 0.1)
				(type default)
			)
			(layer "B.Fab")
		)
		(pad "1" smd rect
			(at 0 0 270)
			(size 0.508 0.508)
			(layers "B.Cu" "B.Mask" "B.Paste")
			(net "VCC_D_3V3")
		)
		(pad "2" smd rect
			(at 0 0.889 270)
			(size 0.508 0.508)
			(layers "B.Cu" "B.Mask" "B.Paste")
			(net "GND")
		)
		(zone
			(layer "B.Cu")
			(hatch none 0.5)
			(connect_pads
				(clearance 0)
			)
			(min_thickness 0.25)
			(keepout
				(tracks allowed)
				(vias not_allowed)
				(pads allowed)
				(copperpour not_allowed)
				(footprints allowed)
			)
			(placement
				(enabled no)
				(sheetname "")
			)
			(fill
				(thermal_gap 0.5)
				(thermal_bridge_width 0.5)
				(island_removal_mode 0)
			)
			(polygon
				(pts
					(xy 418.86886 -30.38856) (xy 418.86886 -29.88056) (xy 419.24986 -29.88056) (xy 419.24986 -30.38856)
				)
			)
		)
		(zone
			(layer "B.Cu")
			(hatch none 0.5)
			(connect_pads
				(clearance 0)
			)
			(min_thickness 0.25)
			(keepout
				(tracks not_allowed)
				(vias allowed)
				(pads allowed)
				(copperpour not_allowed)
				(footprints allowed)
			)
			(placement
				(enabled no)
				(sheetname "")
			)
			(fill
				(thermal_gap 0.5)
				(thermal_bridge_width 0.5)
				(island_removal_mode 0)
			)
			(polygon
				(pts
					(xy 419.24986 -30.38856) (xy 419.24986 -29.88056) (xy 418.86886 -29.88056) (xy 418.86886 -30.38856)
				)
			)
		)
	)
)
